# TIMECARD (Time Appliance Project (Time Card)) — schematic netlist excerpt (pin names and nets, part order shuffled) for the footprints in the layout excerpt that follows; sources: Cadence DE-HDL packaged netlist, KiCad conversion of R4006-B0001-02_R01.brd

R183  RESISTOR  33OHM 1%  pkg SMC_0402R_H016  page 16 : \1\ = EEPROM_I2C_SDA ; \2\ = EEPROM_SDA
R364  RESISTOR  33OHM 1%  pkg SMC_0402R_H016  page 26 : \1\ = RGB_LED_I2C_SDA ; \2\ = R_RGB_LED_I2C_SDA

(kicad_pcb
	(version 20260206)
	(generator "pcbnew")
	(generator_version "10.0")
	(general
		(thickness 1.6)
		(legacy_teardrops no)
	)
	(paper "A4")
	(title_block
		(title "timecard-production-celestica-r4006 — R4006-B0001-02_R01.brd")
		(comment 1 "Time Appliance Project (Time Card) / footprints 330-331 of 1113")
	)
	(layers
		(0 "F.Cu" signal "TOP")
		(4 "In1.Cu" signal "L02_GND1")
		(6 "In2.Cu" signal "L03_SIG1")
		(8 "In3.Cu" signal "L04_GND2")
		(10 "In4.Cu" signal "L05_VCC1")
		(12 "In5.Cu" signal "L06_VCC2")
		(14 "In6.Cu" signal "L07_GND3")
		(16 "In7.Cu" signal "L08_SIG2")
		(18 "In8.Cu" signal "L09_GND4")
		(2 "B.Cu" signal "BOTTOM")
		(9 "F.Adhes" user "F.Adhesive")
		(11 "B.Adhes" user "B.Adhesive")
		(13 "F.Paste" user "Package Geometry/Pastemask Top")
		(15 "B.Paste" user "Package Geometry/Pastemask Bottom")
		(5 "F.SilkS" user "Ref Des/Silkscreen Top")
		(7 "B.SilkS" user "Ref Des/Silkscreen Bottom")
		(1 "F.Mask" user "Board Geometry/Soldermask Top")
		(3 "B.Mask" user "Board Geometry/Soldermask Bottom")
		(17 "Dwgs.User" user "User.Drawings")
		(19 "Cmts.User" user "User.Comments")
		(21 "Eco1.User" user "User.Eco1")
		(23 "Eco2.User" user "User.Eco2")
		(25 "Edge.Cuts" user "Board Geometry/Outline")
		(27 "Margin" user)
		(31 "F.CrtYd" user "Package Geometry/Place Bound Top")
		(29 "B.CrtYd" user "Package Geometry/Place Bound Bottom")
		(35 "F.Fab" user "Ref Des/Assembly Top")
		(33 "B.Fab" user "Ref Des/Assembly Bottom")
	)
	(footprint ""
		(layer "F.Cu")
		(at 111.125 -103.251 180)
		(property "Reference" "R364"
			(at -3.175 3.26263 0)
			(unlocked yes)
			(layer "F.SilkS")
			(effects
				(font
					(size 0.7874 0.5842)
					(thickness 0.1524)
				)
			)
		)
		(property "Value" "VAL*"
			(at 0.02032 2.13233 180)
			(unlocked yes)
			(layer "F.Fab")
			(hide yes)
			(effects
				(font
					(size 0.7874 0.5842)
					(thickness 0.1524)
				)
			)
		)
		(property "Tolerance" "TOL*"
			(at 0.044704 3.05435 180)
			(unlocked yes)
			(layer "Cmts.User")
			(hide yes)
			(effects
				(font
					(size 0.7874 0.5842)
					(thickness 0.1524)
				)
			)
		)
		(property "User Part Number" "PARTNUM*"
			(at 0.02032 4.024884 180)
			(unlocked yes)
			(layer "Cmts.User")
			(hide yes)
			(effects
				(font
					(size 0.7874 0.5842)
					(thickness 0.1524)
				)
			)
		)
		(property "Device Type" "RESISTOR-G155-133R0-01,33OHM,1%"
			(at 0.008382 1.210564 180)
			(unlocked yes)
			(layer "F.Fab")
			(hide yes)
			(effects
				(font
					(size 0.7874 0.5842)
					(thickness 0.1524)
				)
			)
		)
		(duplicate_pad_numbers_are_jumpers no)
		(fp_line
			(start 1.143 0.5588)
			(end 1.143 -0.5588)
			(stroke
				(width 0.1)
				(type default)
			)
			(layer "F.SilkS")
		)
		(fp_line
			(start 1.143 -0.5588)
			(end -1.143 -0.5588)
			(stroke
				(width 0.1)
				(type default)
			)
			(layer "F.SilkS")
		)
		(fp_line
			(start -1.143 0.5588)
			(end 1.143 0.5588)
			(stroke
				(width 0.1)
				(type default)
			)
			(layer "F.SilkS")
		)
		(fp_line
			(start -1.143 -0.5588)
			(end -1.143 0.5588)
			(stroke
				(width 0.1)
				(type default)
			)
			(layer "F.SilkS")
		)
		(fp_poly
			(pts
				(xy -1.143 0.5588) (xy 1.143 0.5588) (xy 1.143 -0.5588) (xy -1.143 -0.5588)
			)
			(stroke
				(width 0)
				(type default)
			)
			(fill no)
			(layer "F.CrtYd")
		)
		(fp_line
			(start 0.508 0.3048)
			(end 0.508 -0.3048)
			(stroke
				(width 0.1)
				(type default)
			)
			(layer "F.Fab")
		)
		(fp_line
			(start 0.508 -0.3048)
			(end -0.508 -0.3048)
			(stroke
				(width 0.1)
				(type default)
			)
			(layer "F.Fab")
		)
		(fp_line
			(start -0.508 0.3048)
			(end 0.508 0.3048)
			(stroke
				(width 0.1)
				(type default)
			)
			(layer "F.Fab")
		)
		(fp_line
			(start -0.508 -0.3048)
			(end -0.508 0.3048)
			(stroke
				(width 0.1)
				(type default)
			)
			(layer "F.Fab")
		)
		(pad "1" smd rect
			(at -0.5334 0 180)
			(size 0.7112 0.6096)
			(layers "F.Cu" "F.Mask" "F.Paste")
			(net "RGB_LED_I2C_SDA")
		)
		(pad "2" smd rect
			(at 0.5334 0 180)
			(size 0.7112 0.6096)
			(layers "F.Cu" "F.Mask" "F.Paste")
			(net "R_RGB_LED_I2C_SDA")
		)
		(zone
			(layer "F.Cu")
			(hatch none 0.5)
			(connect_pads
				(clearance 0)
			)
			(min_thickness 0.25)
			(keepout
				(tracks allowed)
				(vias not_allowed)
				(pads allowed)
				(copperpour not_allowed)
				(footprints allowed)
			)
			(placement
				(enabled no)
				(sheetname "")
			)
			(fill
				(thermal_gap 0.5)
				(thermal_bridge_width 0.5)
				(island_removal_mode 0)
			)
			(polygon
				(pts
					(xy 111.2012 -103.5558) (xy 111.0488 -103.5558) (xy 111.0488 -102.9462) (xy 111.2012 -102.9462)
				)
			)
		)
		(zone
			(layer "F.Cu")
			(hatch none 0.5)
			(connect_pads
				(clearance 0)
			)
			(min_thickness 0.25)
			(keepout
				(tracks not_allowed)
				(vias allowed)
				(pads allowed)
				(copperpour not_allowed)
				(footprints allowed)
			)
			(placement
				(enabled no)
				(sheetname "")
			)
			(fill
				(thermal_gap 0.5)
				(thermal_bridge_width 0.5)
				(island_removal_mode 0)
			)
			(polygon
				(pts
					(xy 111.2012 -103.5558) (xy 111.0488 -103.5558) (xy 111.0488 -102.9462) (xy 111.2012 -102.9462)
				)
			)
		)
	)
	(footprint ""
		(layer "F.Cu")
		(at 33.7693 -15.5702 180)
		(property "Reference" "R183"
			(at -2.6543 -2.07137 0)
			(unlocked yes)
			(layer "F.SilkS")
			(effects
				(font
					(size 0.7874 0.5842)
					(thickness 0.1524)
				)
			)
		)
		(property "Value" "VAL*"
			(at 0.02032 2.13233 180)
			(unlocked yes)
			(layer "F.Fab")
			(hide yes)
			(effects
				(font
					(size 0.7874 0.5842)
					(thickness 0.1524)
				)
			)
		)
		(property "Tolerance" "TOL*"
			(at 0.044704 3.05435 180)
			(unlocked yes)
			(layer "Cmts.User")
			(hide yes)
			(effects
				(font
					(size 0.7874 0.5842)
					(thickness 0.1524)
				)
			)
		)
		(property "User Part Number" "PARTNUM*"
			(at 0.02032 4.024884 180)
			(unlocked yes)
			(layer "Cmts.User")
			(hide yes)
			(effects
				(font
					(size 0.7874 0.5842)
					(thickness 0.1524)
				)
			)
		)
		(property "Device Type" "RESISTOR-G155-133R0-01,33OHM,1%"
			(at 0.008382 1.210564 180)
			(unlocked yes)
			(layer "F.Fab")
			(hide yes)
			(effects
				(font
					(size 0.7874 0.5842)
					(thickness 0.1524)
				)
			)
		)
		(duplicate_pad_numbers_are_jumpers no)
		(fp_line
			(start 1.143 0.5588)
			(end 1.143 -0.5588)
			(stroke
				(width 0.1)
				(type default)
			)
			(layer "F.SilkS")
		)
		(fp_line
			(start 1.143 -0.5588)
			(end -1.143 -0.5588)
			(stroke
				(width 0.1)
				(type default)
			)
			(layer "F.SilkS")
		)
		(fp_line
			(start -1.143 0.5588)
			(end 1.143 0.5588)
			(stroke
				(width 0.1)
				(type default)
			)
			(layer "F.SilkS")
		)
		(fp_line
			(start -1.143 -0.5588)
			(end -1.143 0.5588)
			(stroke
				(width 0.1)
				(type default)
			)
			(layer "F.SilkS")
		)
		(fp_rect
			(start 1.143 -0.5588)
			(end -1.143 0.5588)
			(stroke
				(width 0)
				(type default)
			)
			(fill no)
			(layer "F.CrtYd")
		)
		(fp_line
			(start 0.508 0.3048)
			(end 0.508 -0.3048)
			(stroke
				(width 0.1)
				(type default)
			)
			(layer "F.Fab")
		)
		(fp_line
			(start 0.508 -0.3048)
			(end -0.508 -0.3048)
			(stroke
				(width 0.1)
				(type default)
			)
			(layer "F.Fab")
		)
		(fp_line
			(start -0.508 0.3048)
			(end 0.508 0.3048)
			(stroke
				(width 0.1)
				(type default)
			)
			(layer "F.Fab")
		)
		(fp_line
			(start -0.508 -0.3048)
			(end -0.508 0.3048)
			(stroke
				(width 0.1)
				(type default)
			)
			(layer "F.Fab")
		)
		(pad "1" smd rect
			(at -0.5334 0 180)
			(size 0.7112 0.6096)
			(layers "F.Cu" "F.Mask" "F.Paste")
			(net "EEPROM_I2C_SDA")
		)
		(pad "2" smd rect
			(at 0.5334 0 180)
			(size 0.7112 0.6096)
			(layers "F.Cu" "F.Mask" "F.Paste")
			(net "EEPROM_SDA")
		)
		(zone
			(layer "F.Cu")
			(hatch none 0.5)
			(connect_pads
				(clearance 0)
			)
			(min_thickness 0.25)
			(keepout
				(tracks allowed)
				(vias not_allowed)
				(pads allowed)
				(copperpour not_allowed)
				(footprints allowed)
			)
			(placement
				(enabled no)
				(sheetname "")
			)
			(fill
				(thermal_gap 0.5)
				(thermal_bridge_width 0.5)
				(island_removal_mode 0)
			)
			(polygon
				(pts
					(xy 33.6931 -15.2654) (xy 33.8455 -15.2654) (xy 33.8455 -15.875) (xy 33.6931 -15.875)
				)
			)
		)
	)
)
